# S9S_MB_2U (Grand Teton) — schematic netlist excerpt (pin names and nets, part order shuffled) for the footprints in the layout excerpt that follows; sources: Cadence DE-HDL packaged netlist, KiCad conversion of 03242023_DA0F0TMBIJ0_F0T_Motherboard_J_brd_V01_OCP.brd

PC1257  Q_CAP  22UF 4V 20% X6S  pkg C0805  page 281 : A = PVPP_HBM_CPU0 ; B = GND
D48  SCHOTTKY_12  B0530WS7F IC  pkg SOD323XB  page 115 : A = PWRGD_FAIL_CPU1_EF_R1 ; C = P3V3_AUX

(kicad_pcb
	(version 20260206)
	(generator "pcbnew")
	(generator_version "10.0")
	(general
		(thickness 1.6)
		(legacy_teardrops no)
	)
	(paper "A4")
	(title_block
		(title "03242023_DA0F0TMBIJ0_F0T_Motherboard_J_brd_V01_OCP.brd")
		(comment 1 "Grand Teton / footprints 4319-4320 of 6105")
	)
	(layers
		(0 "F.Cu" signal "TOP")
		(4 "In1.Cu" signal "GND")
		(6 "In2.Cu" signal "IN1")
		(8 "In3.Cu" signal "GND1")
		(10 "In4.Cu" signal "IN2")
		(12 "In5.Cu" signal "GND2")
		(14 "In6.Cu" signal "IN3")
		(16 "In7.Cu" signal "GND3")
		(18 "In8.Cu" signal "VCC")
		(20 "In9.Cu" signal "VCC1")
		(22 "In10.Cu" signal "GND4")
		(24 "In11.Cu" signal "IN4")
		(26 "In12.Cu" signal "GND5")
		(28 "In13.Cu" signal "IN5")
		(30 "In14.Cu" signal "GND6")
		(32 "In15.Cu" signal "IN6")
		(34 "In16.Cu" signal "GND7")
		(2 "B.Cu" signal "BOTTOM")
		(9 "F.Adhes" user "F.Adhesive")
		(11 "B.Adhes" user "B.Adhesive")
		(13 "F.Paste" user "Package Geometry/Pastemask Top")
		(15 "B.Paste" user "Package Geometry/Pastemask Bottom")
		(5 "F.SilkS" user "Ref Des/Silkscreen Top")
		(7 "B.SilkS" user "Ref Des/Silkscreen Bottom")
		(1 "F.Mask" user "Board Geometry/Soldermask Top")
		(3 "B.Mask" user "Board Geometry/Soldermask Bottom")
		(17 "Dwgs.User" user "User.Drawings")
		(19 "Cmts.User" user "User.Comments")
		(21 "Eco1.User" user "User.Eco1")
		(23 "Eco2.User" user "User.Eco2")
		(25 "Edge.Cuts" user "Board Geometry/Outline")
		(27 "Margin" user)
		(31 "F.CrtYd" user "Package Geometry/Place Bound Top")
		(29 "B.CrtYd" user "Package Geometry/Place Bound Bottom")
		(35 "F.Fab" user "Ref Des/Assembly Top")
		(33 "B.Fab" user "Ref Des/Assembly Bottom")
	)
	(footprint ""
		(layer "B.Cu")
		(at 185.368438 -315.458602 180)
		(property "Reference" "D48"
			(at 2.132838 -2.945384 0)
			(unlocked yes)
			(layer "B.SilkS")
			(effects
				(font
					(size 0.7874 0.5842)
					(thickness 0.1524)
				)
				(justify left mirror)
			)
		)
		(property "Value" ""
			(at 0 0 0)
			(layer "B.Fab")
			(effects
				(font
					(size 1.27 1.27)
				)
				(justify mirror)
			)
		)
		(duplicate_pad_numbers_are_jumpers no)
		(fp_line
			(start 2.050796 0.700024)
			(end 2.050796 -0.700024)
			(stroke
				(width 0.1524)
				(type default)
			)
			(layer "B.SilkS")
		)
		(fp_line
			(start 2.050796 -0.700024)
			(end -2.050796 -0.700024)
			(stroke
				(width 0.1524)
				(type default)
			)
			(layer "B.SilkS")
		)
		(fp_line
			(start 0.30607 0.500126)
			(end -0.193802 0)
			(stroke
				(width 0.1524)
				(type default)
			)
			(layer "B.SilkS")
		)
		(fp_line
			(start 0.30607 -0.500126)
			(end 0.30607 0.500126)
			(stroke
				(width 0.1524)
				(type default)
			)
			(layer "B.SilkS")
		)
		(fp_line
			(start -0.193802 0)
			(end 0.30607 -0.500126)
			(stroke
				(width 0.1524)
				(type default)
			)
			(layer "B.SilkS")
		)
		(fp_line
			(start -0.293878 -0.500126)
			(end -0.293878 0.500126)
			(stroke
				(width 0.1524)
				(type default)
			)
			(layer "B.SilkS")
		)
		(fp_line
			(start -2.050796 0.700024)
			(end 2.050796 0.700024)
			(stroke
				(width 0.1524)
				(type default)
			)
			(layer "B.SilkS")
		)
		(fp_line
			(start -2.050796 -0.700024)
			(end -2.050796 0.700024)
			(stroke
				(width 0.1524)
				(type default)
			)
			(layer "B.SilkS")
		)
		(fp_line
			(start -2.051304 0.6985)
			(end -2.051304 0.635)
			(stroke
				(width 0.1524)
				(type default)
			)
			(layer "B.SilkS")
		)
		(fp_line
			(start -2.051304 0.635)
			(end -2.152904 0.635)
			(stroke
				(width 0.1524)
				(type default)
			)
			(layer "B.SilkS")
		)
		(fp_line
			(start -2.064004 -0.6731)
			(end -2.064004 -0.6985)
			(stroke
				(width 0.1524)
				(type default)
			)
			(layer "B.SilkS")
		)
		(fp_line
			(start -2.064004 -0.6985)
			(end -2.229104 -0.6985)
			(stroke
				(width 0.1524)
				(type default)
			)
			(layer "B.SilkS")
		)
		(fp_line
			(start -2.152904 0.635)
			(end -2.152904 -0.6985)
			(stroke
				(width 0.1524)
				(type default)
			)
			(layer "B.SilkS")
		)
		(fp_line
			(start -2.152904 -0.6985)
			(end -2.343404 -0.6985)
			(stroke
				(width 0.1524)
				(type default)
			)
			(layer "B.SilkS")
		)
		(fp_line
			(start -2.229104 0.6985)
			(end -2.051304 0.6985)
			(stroke
				(width 0.1524)
				(type default)
			)
			(layer "B.SilkS")
		)
		(fp_line
			(start -2.229104 -0.6985)
			(end -2.229104 0.6985)
			(stroke
				(width 0.1524)
				(type default)
			)
			(layer "B.SilkS")
		)
		(fp_line
			(start -2.343404 0.6985)
			(end -2.216404 0.6985)
			(stroke
				(width 0.1524)
				(type default)
			)
			(layer "B.SilkS")
		)
		(fp_line
			(start -2.343404 -0.6985)
			(end -2.343404 0.6985)
			(stroke
				(width 0.1524)
				(type default)
			)
			(layer "B.SilkS")
		)
		(fp_line
			(start 0.899922 0.700024)
			(end 0.899922 -0.700024)
			(stroke
				(width 0.1)
				(type default)
			)
			(layer "B.Fab")
		)
		(fp_line
			(start 0.899922 -0.700024)
			(end -0.899922 -0.700024)
			(stroke
				(width 0.1)
				(type default)
			)
			(layer "B.Fab")
		)
		(fp_line
			(start -0.899922 0.700024)
			(end 0.899922 0.700024)
			(stroke
				(width 0.1)
				(type default)
			)
			(layer "B.Fab")
		)
		(fp_line
			(start -0.899922 -0.700024)
			(end -0.899922 0.700024)
			(stroke
				(width 0.1)
				(type default)
			)
			(layer "B.Fab")
		)
		(fp_text user "+"
			(at 3.123946 0.762 90)
			(unlocked yes)
			(layer "B.SilkS")
			(effects
				(font
					(size 1.905 1.4224)
					(thickness 0.1524)
				)
				(justify left mirror)
			)
		)
		(fp_text user "-"
			(at -3.869182 -0.885444 0)
			(unlocked yes)
			(layer "B.SilkS")
			(effects
				(font
					(size 1.905 1.4224)
					(thickness 0.1524)
				)
				(justify left mirror)
			)
		)
		(fp_text user "+"
			(at 3.123946 0.762 90)
			(unlocked yes)
			(layer "B.Fab")
			(effects
				(font
					(size 1.905 1.4224)
					(thickness 0.1524)
				)
				(justify left mirror)
			)
		)
		(fp_text user "-"
			(at -3.880104 0.23495 0)
			(unlocked yes)
			(layer "B.Fab")
			(effects
				(font
					(size 1.905 1.4224)
					(thickness 0.1524)
				)
				(justify left mirror)
			)
		)
		(pad "1" smd rect
			(at 1.199896 0 90)
			(size 0.6604 1.3716)
			(layers "B.Cu" "B.Mask" "B.Paste")
			(net "PWRGD_FAIL_CPU1_EF_R1")
		)
		(pad "2" smd rect
			(at -1.199896 0 270)
			(size 0.6604 1.3716)
			(layers "B.Cu" "B.Mask" "B.Paste")
			(net "P3V3_AUX")
		)
	)
	(footprint ""
		(layer "B.Cu")
		(at 371.676676 -366.755426 90)
		(property "Reference" "PC1257"
			(at 0 0 90)
			(layer "B.SilkS")
			(hide yes)
			(effects
				(font
					(size 1.27 1.27)
				)
				(justify mirror)
			)
		)
		(property "Value" ""
			(at 0 0 90)
			(layer "B.Fab")
			(effects
				(font
					(size 1.27 1.27)
				)
				(justify mirror)
			)
		)
		(duplicate_pad_numbers_are_jumpers no)
		(fp_line
			(start 1.524 -0.762)
			(end -1.524 -0.762)
			(stroke
				(width 0.1524)
				(type default)
			)
			(layer "B.SilkS")
		)
		(fp_line
			(start -1.524 -0.762)
			(end -1.524 0.762)
			(stroke
				(width 0.1524)
				(type default)
			)
			(layer "B.SilkS")
		)
		(fp_line
			(start 1.524 0.762)
			(end 1.524 -0.762)
			(stroke
				(width 0.1524)
				(type default)
			)
			(layer "B.SilkS")
		)
		(fp_line
			(start -1.524 0.762)
			(end 1.524 0.762)
			(stroke
				(width 0.1524)
				(type default)
			)
			(layer "B.SilkS")
		)
		(fp_line
			(start 1.1049 -0.724916)
			(end 1.1049 0.724916)
			(stroke
				(width 0.1)
				(type default)
			)
			(layer "B.Fab")
		)
		(fp_line
			(start -1.1049 -0.724916)
			(end 1.1049 -0.724916)
			(stroke
				(width 0.1)
				(type default)
			)
			(layer "B.Fab")
		)
		(fp_line
			(start 1.1049 0.724916)
			(end -1.1049 0.724916)
			(stroke
				(width 0.1)
				(type default)
			)
			(layer "B.Fab")
		)
		(fp_line
			(start -1.1049 0.724916)
			(end -1.1049 -0.724916)
			(stroke
				(width 0.1)
				(type default)
			)
			(layer "B.Fab")
		)
		(pad "1" smd rect
			(at 0.889 0 90)
			(size 1.016 1.27)
			(layers "B.Cu" "B.Mask" "B.Paste")
			(net "PVPP_HBM_CPU0")
		)
		(pad "2" smd rect
			(at -0.889 0 90)
			(size 1.016 1.27)
			(layers "B.Cu" "B.Mask" "B.Paste")
			(net "GND")
		)
	)
)
